(kicad_pcb
	(version 20260206)
	(generator "pcbnew")
	(generator_version "10.0")
	(general
		(thickness 1.6)
		(legacy_teardrops no)
	)
	(paper "A4")
	(title_block
		(title "12092022_DA0F0TMDCD0_F0T_Management_Board_D_brd_V3_OCP.brd")
		(comment 1 "Grand Teton / footprints 191-196 of 1440")
	)
	(layers
		(0 "F.Cu" signal "TOP")
		(4 "In1.Cu" signal "GND")
		(6 "In2.Cu" signal "IN1")
		(8 "In3.Cu" signal "GND1")
		(10 "In4.Cu" signal "IN2")
		(12 "In5.Cu" signal "VCC")
		(14 "In6.Cu" signal "VCC1")
		(16 "In7.Cu" signal "IN3")
		(18 "In8.Cu" signal "GND2")
		(20 "In9.Cu" signal "IN4")
		(22 "In10.Cu" signal "GND3")
		(2 "B.Cu" signal "BOTTOM")
		(9 "F.Adhes" user "F.Adhesive")
		(11 "B.Adhes" user "B.Adhesive")
		(13 "F.Paste" user "Package Geometry/Pastemask Top")
		(15 "B.Paste" user "Package Geometry/Pastemask Bottom")
		(5 "F.SilkS" user "Ref Des/Silkscreen Top")
		(7 "B.SilkS" user "Ref Des/Silkscreen Bottom")
		(1 "F.Mask" user "Board Geometry/Soldermask Top")
		(3 "B.Mask" user "Board Geometry/Soldermask Bottom")
		(17 "Dwgs.User" user "User.Drawings")
		(19 "Cmts.User" user "User.Comments")
		(21 "Eco1.User" user "User.Eco1")
		(23 "Eco2.User" user "User.Eco2")
		(25 "Edge.Cuts" user "Board Geometry/Outline")
		(27 "Margin" user)
		(31 "F.CrtYd" user "Package Geometry/Place Bound Top")
		(29 "B.CrtYd" user "Package Geometry/Place Bound Bottom")
		(35 "F.Fab" user "Ref Des/Assembly Top")
		(33 "B.Fab" user "Ref Des/Assembly Bottom")
	)
	(footprint ""
		(layer "F.Cu")
		(at 30.41904 -68.504054 90)
		(property "Reference" "R661"
			(at 0 0 90)
			(layer "F.SilkS")
			(hide yes)
			(effects
				(font
					(size 1.27 1.27)
				)
			)
		)
		(property "Value" ""
			(at 0 0 90)
			(layer "F.Fab")
			(effects
				(font
					(size 1.27 1.27)
				)
			)
		)
		(duplicate_pad_numbers_are_jumpers no)
		(fp_line
			(start 0.7874 -0.4064)
			(end 0.7874 0.4064)
			(stroke
				(width 0.1524)
				(type default)
			)
			(layer "F.SilkS")
		)
		(fp_line
			(start -0.7874 -0.4064)
			(end 0.7874 -0.4064)
			(stroke
				(width 0.1524)
				(type default)
			)
			(layer "F.SilkS")
		)
		(fp_line
			(start 0.7874 0.4064)
			(end -0.7874 0.4064)
			(stroke
				(width 0.1524)
				(type default)
			)
			(layer "F.SilkS")
		)
		(fp_line
			(start -0.7874 0.4064)
			(end -0.7874 -0.4064)
			(stroke
				(width 0.1524)
				(type default)
			)
			(layer "F.SilkS")
		)
		(fp_line
			(start -0.12065 -0.305054)
			(end -0.12065 -0.2794)
			(stroke
				(width 0.1)
				(type default)
			)
			(layer "F.Fab")
		)
		(fp_line
			(start -0.67945 -0.305054)
			(end -0.12065 -0.305054)
			(stroke
				(width 0.1)
				(type default)
			)
			(layer "F.Fab")
		)
		(fp_line
			(start 0.67945 -0.3048)
			(end 0.67945 0.3048)
			(stroke
				(width 0.1)
				(type default)
			)
			(layer "F.Fab")
		)
		(fp_line
			(start 0.12065 -0.3048)
			(end 0.67945 -0.3048)
			(stroke
				(width 0.1)
				(type default)
			)
			(layer "F.Fab")
		)
		(fp_line
			(start 0.12065 -0.2794)
			(end 0.12065 -0.3048)
			(stroke
				(width 0.1)
				(type default)
			)
			(layer "F.Fab")
		)
		(fp_line
			(start -0.12065 -0.2794)
			(end 0.12065 -0.2794)
			(stroke
				(width 0.1)
				(type default)
			)
			(layer "F.Fab")
		)
		(fp_line
			(start 0.120396 0.2794)
			(end -0.12065 0.2794)
			(stroke
				(width 0.1)
				(type default)
			)
			(layer "F.Fab")
		)
		(fp_line
			(start -0.12065 0.2794)
			(end -0.12065 0.3048)
			(stroke
				(width 0.1)
				(type default)
			)
			(layer "F.Fab")
		)
		(fp_line
			(start 0.67945 0.3048)
			(end 0.120396 0.3048)
			(stroke
				(width 0.1)
				(type default)
			)
			(layer "F.Fab")
		)
		(fp_line
			(start 0.120396 0.3048)
			(end 0.120396 0.2794)
			(stroke
				(width 0.1)
				(type default)
			)
			(layer "F.Fab")
		)
		(fp_line
			(start -0.12065 0.3048)
			(end -0.67945 0.3048)
			(stroke
				(width 0.1)
				(type default)
			)
			(layer "F.Fab")
		)
		(fp_line
			(start -0.67945 0.3048)
			(end -0.67945 -0.305054)
			(stroke
				(width 0.1)
				(type default)
			)
			(layer "F.Fab")
		)
		(pad "1" smd circle
			(at -0.40005 0 90)
			(size 0 0)
			(layers "F.Cu" "F.Mask" "F.Paste")
			(net "P3V3_AUX")
		)
		(pad "2" smd circle
			(at 0.40005 0 90)
			(size 0 0)
			(layers "F.Cu" "F.Mask" "F.Paste")
			(net "EMMC_DT6_R")
		)
	)
	(footprint ""
		(layer "F.Cu")
		(at 16.230092 -6.290056)
		(property "Reference" "D14"
			(at 1.448308 -2.547874 0)
			(unlocked yes)
			(layer "F.SilkS")
			(effects
				(font
					(size 0.7874 0.5842)
					(thickness 0.1524)
				)
				(justify left)
			)
		)
		(property "Value" ""
			(at 0 0 0)
			(layer "F.Fab")
			(effects
				(font
					(size 1.27 1.27)
				)
			)
		)
		(duplicate_pad_numbers_are_jumpers no)
		(fp_line
			(start -1.080008 -1.999996)
			(end 3.620008 -1.999996)
			(stroke
				(width 0.1524)
				(type default)
			)
			(layer "F.SilkS")
		)
		(fp_line
			(start -1.080008 3.999992)
			(end -1.080008 -1.999996)
			(stroke
				(width 0.1524)
				(type default)
			)
			(layer "F.SilkS")
		)
		(fp_line
			(start -0.230124 3.999992)
			(end -1.080008 3.999992)
			(stroke
				(width 0.1524)
				(type default)
			)
			(layer "F.SilkS")
		)
		(fp_line
			(start -0.230124 5.199888)
			(end -0.230124 3.999992)
			(stroke
				(width 0.1524)
				(type default)
			)
			(layer "F.SilkS")
		)
		(fp_line
			(start 2.770124 3.999992)
			(end 2.770124 5.199888)
			(stroke
				(width 0.1524)
				(type default)
			)
			(layer "F.SilkS")
		)
		(fp_line
			(start 3.620008 -1.999996)
			(end 3.620008 3.999992)
			(stroke
				(width 0.1524)
				(type default)
			)
			(layer "F.SilkS")
		)
		(fp_line
			(start 3.620008 3.999992)
			(end 2.770124 3.999992)
			(stroke
				(width 0.1524)
				(type default)
			)
			(layer "F.SilkS")
		)
		(fp_arc
			(start 1.27 6.700012)
			(mid 0.209252 6.260636)
			(end -0.230124 5.199888)
			(stroke
				(width 0.1524)
				(type default)
			)
			(layer "F.SilkS")
		)
		(fp_arc
			(start 2.770124 5.199888)
			(mid 2.330748 6.260636)
			(end 1.27 6.700012)
			(stroke
				(width 0.1524)
				(type default)
			)
			(layer "F.SilkS")
		)
		(fp_line
			(start -1.080008 -1.999996)
			(end 3.620008 -1.999996)
			(stroke
				(width 0.1)
				(type default)
			)
			(layer "F.Fab")
		)
		(fp_line
			(start -1.080008 3.999992)
			(end -1.080008 -1.999996)
			(stroke
				(width 0.1)
				(type default)
			)
			(layer "F.Fab")
		)
		(fp_line
			(start -0.230124 3.999992)
			(end -1.080008 3.999992)
			(stroke
				(width 0.1)
				(type default)
			)
			(layer "F.Fab")
		)
		(fp_line
			(start -0.230124 5.199888)
			(end -0.230124 3.999992)
			(stroke
				(width 0.1)
				(type default)
			)
			(layer "F.Fab")
		)
		(fp_line
			(start 2.770124 3.999992)
			(end 2.770124 5.199888)
			(stroke
				(width 0.1)
				(type default)
			)
			(layer "F.Fab")
		)
		(fp_line
			(start 3.620008 -1.999996)
			(end 3.620008 3.999992)
			(stroke
				(width 0.1)
				(type default)
			)
			(layer "F.Fab")
		)
		(fp_line
			(start 3.620008 3.999992)
			(end 2.770124 3.999992)
			(stroke
				(width 0.1)
				(type default)
			)
			(layer "F.Fab")
		)
		(fp_arc
			(start 1.27 6.700012)
			(mid 0.209252 6.260636)
			(end -0.230124 5.199888)
			(stroke
				(width 0.1)
				(type default)
			)
			(layer "F.Fab")
		)
		(fp_arc
			(start 2.770124 5.199888)
			(mid 2.330748 6.260636)
			(end 1.27 6.700012)
			(stroke
				(width 0.1)
				(type default)
			)
			(layer "F.Fab")
		)
		(pad "A" thru_hole rect
			(at 0 0)
			(size 1.2192 1.2192)
			(drill 0.8128)
			(layers "*.Cu" "*.Mask")
			(remove_unused_layers no)
			(net "PWR_LED_P5V_AUX")
			(clearance 0.0508)
			(thermal_gap 0.0508)
			(padstack
				(mode front_inner_back)
				(layer "Inner"
					(shape circle)
					(size 1.2192 1.2192)
					(clearance 0.0508)
				)
				(layer "B.Cu"
					(shape rect)
					(size 1.2192 1.2192)
					(clearance 0.0508)
				)
			)
		)
		(pad "C" thru_hole circle
			(at 2.54 0)
			(size 1.2192 1.2192)
			(drill 0.8128)
			(layers "*.Cu" "*.Mask")
			(remove_unused_layers no)
			(net "PWR_LED_BUF_N_R")
			(clearance 0.0508)
			(thermal_gap 0.0508)
		)
	)
	(footprint ""
		(layer "F.Cu")
		(at 26.289 -68.834 90)
		(property "Reference" "R58"
			(at 0 0 90)
			(layer "F.SilkS")
			(hide yes)
			(effects
				(font
					(size 1.27 1.27)
				)
			)
		)
		(property "Value" ""
			(at 0 0 90)
			(layer "F.Fab")
			(effects
				(font
					(size 1.27 1.27)
				)
			)
		)
		(duplicate_pad_numbers_are_jumpers no)
		(fp_line
			(start 0.7874 -0.4064)
			(end 0.7874 0.4064)
			(stroke
				(width 0.1524)
				(type default)
			)
			(layer "F.SilkS")
		)
		(fp_line
			(start -0.7874 -0.4064)
			(end 0.7874 -0.4064)
			(stroke
				(width 0.1524)
				(type default)
			)
			(layer "F.SilkS")
		)
		(fp_line
			(start 0.7874 0.4064)
			(end -0.7874 0.4064)
			(stroke
				(width 0.1524)
				(type default)
			)
			(layer "F.SilkS")
		)
		(fp_line
			(start -0.7874 0.4064)
			(end -0.7874 -0.4064)
			(stroke
				(width 0.1524)
				(type default)
			)
			(layer "F.SilkS")
		)
		(fp_line
			(start -0.12065 -0.305054)
			(end -0.12065 -0.2794)
			(stroke
				(width 0.1)
				(type default)
			)
			(layer "F.Fab")
		)
		(fp_line
			(start -0.67945 -0.305054)
			(end -0.12065 -0.305054)
			(stroke
				(width 0.1)
				(type default)
			)
			(layer "F.Fab")
		)
		(fp_line
			(start 0.67945 -0.3048)
			(end 0.67945 0.3048)
			(stroke
				(width 0.1)
				(type default)
			)
			(layer "F.Fab")
		)
		(fp_line
			(start 0.12065 -0.3048)
			(end 0.67945 -0.3048)
			(stroke
				(width 0.1)
				(type default)
			)
			(layer "F.Fab")
		)
		(fp_line
			(start 0.12065 -0.2794)
			(end 0.12065 -0.3048)
			(stroke
				(width 0.1)
				(type default)
			)
			(layer "F.Fab")
		)
		(fp_line
			(start -0.12065 -0.2794)
			(end 0.12065 -0.2794)
			(stroke
				(width 0.1)
				(type default)
			)
			(layer "F.Fab")
		)
		(fp_line
			(start 0.120396 0.2794)
			(end -0.12065 0.2794)
			(stroke
				(width 0.1)
				(type default)
			)
			(layer "F.Fab")
		)
		(fp_line
			(start -0.12065 0.2794)
			(end -0.12065 0.3048)
			(stroke
				(width 0.1)
				(type default)
			)
			(layer "F.Fab")
		)
		(fp_line
			(start 0.67945 0.3048)
			(end 0.120396 0.3048)
			(stroke
				(width 0.1)
				(type default)
			)
			(layer "F.Fab")
		)
		(fp_line
			(start 0.120396 0.3048)
			(end 0.120396 0.2794)
			(stroke
				(width 0.1)
				(type default)
			)
			(layer "F.Fab")
		)
		(fp_line
			(start -0.12065 0.3048)
			(end -0.67945 0.3048)
			(stroke
				(width 0.1)
				(type default)
			)
			(layer "F.Fab")
		)
		(fp_line
			(start -0.67945 0.3048)
			(end -0.67945 -0.305054)
			(stroke
				(width 0.1)
				(type default)
			)
			(layer "F.Fab")
		)
		(pad "1" smd circle
			(at -0.40005 0 90)
			(size 0 0)
			(layers "F.Cu" "F.Mask" "F.Paste")
			(net "P3V3_AUX")
		)
		(pad "2" smd circle
			(at 0.40005 0 90)
			(size 0 0)
			(layers "F.Cu" "F.Mask" "F.Paste")
			(net "SPI_BMC_HOLD0_N")
		)
	)
	(footprint ""
		(layer "F.Cu")
		(at 73.980294 -99.4664)
		(property "Reference" "R33"
			(at 0 0 0)
			(layer "F.SilkS")
			(hide yes)
			(effects
				(font
					(size 1.27 1.27)
				)
			)
		)
		(property "Value" ""
			(at 0 0 0)
			(layer "F.Fab")
			(effects
				(font
					(size 1.27 1.27)
				)
			)
		)
		(duplicate_pad_numbers_are_jumpers no)
		(fp_line
			(start -0.7874 -0.4064)
			(end 0.7874 -0.4064)
			(stroke
				(width 0.1524)
				(type default)
			)
			(layer "F.SilkS")
		)
		(fp_line
			(start -0.7874 0.4064)
			(end -0.7874 -0.4064)
			(stroke
				(width 0.1524)
				(type default)
			)
			(layer "F.SilkS")
		)
		(fp_line
			(start 0.7874 -0.4064)
			(end 0.7874 0.4064)
			(stroke
				(width 0.1524)
				(type default)
			)
			(layer "F.SilkS")
		)
		(fp_line
			(start 0.7874 0.4064)
			(end -0.7874 0.4064)
			(stroke
				(width 0.1524)
				(type default)
			)
			(layer "F.SilkS")
		)
		(fp_line
			(start -0.67945 -0.305054)
			(end -0.12065 -0.305054)
			(stroke
				(width 0.1)
				(type default)
			)
			(layer "F.Fab")
		)
		(fp_line
			(start -0.67945 0.3048)
			(end -0.67945 -0.305054)
			(stroke
				(width 0.1)
				(type default)
			)
			(layer "F.Fab")
		)
		(fp_line
			(start -0.12065 -0.305054)
			(end -0.12065 -0.2794)
			(stroke
				(width 0.1)
				(type default)
			)
			(layer "F.Fab")
		)
		(fp_line
			(start -0.12065 -0.2794)
			(end 0.12065 -0.2794)
			(stroke
				(width 0.1)
				(type default)
			)
			(layer "F.Fab")
		)
		(fp_line
			(start -0.12065 0.2794)
			(end -0.12065 0.3048)
			(stroke
				(width 0.1)
				(type default)
			)
			(layer "F.Fab")
		)
		(fp_line
			(start -0.12065 0.3048)
			(end -0.67945 0.3048)
			(stroke
				(width 0.1)
				(type default)
			)
			(layer "F.Fab")
		)
		(fp_line
			(start 0.120396 0.2794)
			(end -0.12065 0.2794)
			(stroke
				(width 0.1)
				(type default)
			)
			(layer "F.Fab")
		)
		(fp_line
			(start 0.120396 0.3048)
			(end 0.120396 0.2794)
			(stroke
				(width 0.1)
				(type default)
			)
			(layer "F.Fab")
		)
		(fp_line
			(start 0.12065 -0.3048)
			(end 0.67945 -0.3048)
			(stroke
				(width 0.1)
				(type default)
			)
			(layer "F.Fab")
		)
		(fp_line
			(start 0.12065 -0.2794)
			(end 0.12065 -0.3048)
			(stroke
				(width 0.1)
				(type default)
			)
			(layer "F.Fab")
		)
		(fp_line
			(start 0.67945 -0.3048)
			(end 0.67945 0.3048)
			(stroke
				(width 0.1)
				(type default)
			)
			(layer "F.Fab")
		)
		(fp_line
			(start 0.67945 0.3048)
			(end 0.120396 0.3048)
			(stroke
				(width 0.1)
				(type default)
			)
			(layer "F.Fab")
		)
		(pad "1" smd circle
			(at -0.40005 0)
			(size 0 0)
			(layers "F.Cu" "F.Mask" "F.Paste")
			(net "SMB_BMC_MM16_R5_SDA")
		)
		(pad "2" smd circle
			(at 0.40005 0)
			(size 0 0)
			(layers "F.Cu" "F.Mask" "F.Paste")
			(net "SMB_BMC_TPM_MM16_SDA")
		)
	)
	(footprint ""
		(layer "F.Cu")
		(at 4.6736 -83.4644 180)
		(property "Reference" "R66"
			(at 0 0 180)
			(layer "F.SilkS")
			(hide yes)
			(effects
				(font
					(size 1.27 1.27)
				)
			)
		)
		(property "Value" ""
			(at 0 0 180)
			(layer "F.Fab")
			(effects
				(font
					(size 1.27 1.27)
				)
			)
		)
		(duplicate_pad_numbers_are_jumpers no)
		(fp_line
			(start 0.7874 0.4064)
			(end -0.7874 0.4064)
			(stroke
				(width 0.1524)
				(type default)
			)
			(layer "F.SilkS")
		)
		(fp_line
			(start 0.7874 -0.4064)
			(end 0.7874 0.4064)
			(stroke
				(width 0.1524)
				(type default)
			)
			(layer "F.SilkS")
		)
		(fp_line
			(start -0.7874 0.4064)
			(end -0.7874 -0.4064)
			(stroke
				(width 0.1524)
				(type default)
			)
			(layer "F.SilkS")
		)
		(fp_line
			(start -0.7874 -0.4064)
			(end 0.7874 -0.4064)
			(stroke
				(width 0.1524)
				(type default)
			)
			(layer "F.SilkS")
		)
		(fp_line
			(start 0.67945 0.3048)
			(end 0.120396 0.3048)
			(stroke
				(width 0.1)
				(type default)
			)
			(layer "F.Fab")
		)
		(fp_line
			(start 0.67945 -0.3048)
			(end 0.67945 0.3048)
			(stroke
				(width 0.1)
				(type default)
			)
			(layer "F.Fab")
		)
		(fp_line
			(start 0.12065 -0.2794)
			(end 0.12065 -0.3048)
			(stroke
				(width 0.1)
				(type default)
			)
			(layer "F.Fab")
		)
		(fp_line
			(start 0.12065 -0.3048)
			(end 0.67945 -0.3048)
			(stroke
				(width 0.1)
				(type default)
			)
			(layer "F.Fab")
		)
		(fp_line
			(start 0.120396 0.3048)
			(end 0.120396 0.2794)
			(stroke
				(width 0.1)
				(type default)
			)
			(layer "F.Fab")
		)
		(fp_line
			(start 0.120396 0.2794)
			(end -0.12065 0.2794)
			(stroke
				(width 0.1)
				(type default)
			)
			(layer "F.Fab")
		)
		(fp_line
			(start -0.12065 0.3048)
			(end -0.67945 0.3048)
			(stroke
				(width 0.1)
				(type default)
			)
			(layer "F.Fab")
		)
		(fp_line
			(start -0.12065 0.2794)
			(end -0.12065 0.3048)
			(stroke
				(width 0.1)
				(type default)
			)
			(layer "F.Fab")
		)
		(fp_line
			(start -0.12065 -0.2794)
			(end 0.12065 -0.2794)
			(stroke
				(width 0.1)
				(type default)
			)
			(layer "F.Fab")
		)
		(fp_line
			(start -0.12065 -0.305054)
			(end -0.12065 -0.2794)
			(stroke
				(width 0.1)
				(type default)
			)
			(layer "F.Fab")
		)
		(fp_line
			(start -0.67945 0.3048)
			(end -0.67945 -0.305054)
			(stroke
				(width 0.1)
				(type default)
			)
			(layer "F.Fab")
		)
		(fp_line
			(start -0.67945 -0.305054)
			(end -0.12065 -0.305054)
			(stroke
				(width 0.1)
				(type default)
			)
			(layer "F.Fab")
		)
		(pad "1" smd circle
			(at -0.40005 0 180)
			(size 0 0)
			(layers "F.Cu" "F.Mask" "F.Paste")
			(net "GND")
		)
		(pad "2" smd circle
			(at 0.40005 0 180)
			(size 0 0)
			(layers "F.Cu" "F.Mask" "F.Paste")
			(net "PWRGD_PSU_AC_PWROK")
		)
	)
	(footprint ""
		(layer "F.Cu")
		(at 82.01152 -70.08876 180)
		(property "Reference" "PC254"
			(at 0 0 180)
			(layer "F.SilkS")
			(hide yes)
			(effects
				(font
					(size 1.27 1.27)
				)
			)
		)
		(property "Value" ""
			(at 0 0 180)
			(layer "F.Fab")
			(effects
				(font
					(size 1.27 1.27)
				)
			)
		)
		(duplicate_pad_numbers_are_jumpers no)
		(fp_line
			(start 0.7874 0.4064)
			(end -0.7874 0.4064)
			(stroke
				(width 0.1524)
				(type default)
			)
			(layer "F.SilkS")
		)
		(fp_line
			(start 0.7874 -0.4064)
			(end 0.7874 0.4064)
			(stroke
				(width 0.1524)
				(type default)
			)
			(layer "F.SilkS")
		)
		(fp_line
			(start -0.7874 0.4064)
			(end -0.7874 -0.4064)
			(stroke
				(width 0.1524)
				(type default)
			)
			(layer "F.SilkS")
		)
		(fp_line
			(start -0.7874 -0.4064)
			(end 0.7874 -0.4064)
			(stroke
				(width 0.1524)
				(type default)
			)
			(layer "F.SilkS")
		)
		(fp_line
			(start 0.67945 0.3048)
			(end 0.120396 0.3048)
			(stroke
				(width 0.1)
				(type default)
			)
			(layer "F.Fab")
		)
		(fp_line
			(start 0.67945 -0.3048)
			(end 0.67945 0.3048)
			(stroke
				(width 0.1)
				(type default)
			)
			(layer "F.Fab")
		)
		(fp_line
			(start 0.12065 -0.2794)
			(end 0.12065 -0.3048)
			(stroke
				(width 0.1)
				(type default)
			)
			(layer "F.Fab")
		)
		(fp_line
			(start 0.12065 -0.3048)
			(end 0.67945 -0.3048)
			(stroke
				(width 0.1)
				(type default)
			)
			(layer "F.Fab")
		)
		(fp_line
			(start 0.120396 0.3048)
			(end 0.120396 0.2794)
			(stroke
				(width 0.1)
				(type default)
			)
			(layer "F.Fab")
		)
		(fp_line
			(start 0.120396 0.2794)
			(end -0.12065 0.2794)
			(stroke
				(width 0.1)
				(type default)
			)
			(layer "F.Fab")
		)
		(fp_line
			(start -0.12065 0.3048)
			(end -0.67945 0.3048)
			(stroke
				(width 0.1)
				(type default)
			)
			(layer "F.Fab")
		)
		(fp_line
			(start -0.12065 0.2794)
			(end -0.12065 0.3048)
			(stroke
				(width 0.1)
				(type default)
			)
			(layer "F.Fab")
		)
		(fp_line
			(start -0.12065 -0.2794)
			(end 0.12065 -0.2794)
			(stroke
				(width 0.1)
				(type default)
			)
			(layer "F.Fab")
		)
		(fp_line
			(start -0.12065 -0.305054)
			(end -0.12065 -0.2794)
			(stroke
				(width 0.1)
				(type default)
			)
			(layer "F.Fab")
		)
		(fp_line
			(start -0.67945 0.3048)
			(end -0.67945 -0.305054)
			(stroke
				(width 0.1)
				(type default)
			)
			(layer "F.Fab")
		)
		(fp_line
			(start -0.67945 -0.305054)
			(end -0.12065 -0.305054)
			(stroke
				(width 0.1)
				(type default)
			)
			(layer "F.Fab")
		)
		(pad "1" smd circle
			(at -0.40005 0 180)
			(size 0 0)
			(layers "F.Cu" "F.Mask" "F.Paste")
			(net "SW_P1V2_AUX_BST")
		)
		(pad "2" smd circle
			(at 0.40005 0 180)
			(size 0 0)
			(layers "F.Cu" "F.Mask" "F.Paste")
			(net "SW_P1V2_AUX_SW")
		)
	)
)
